(kicad_sch
	(version 20250114)
	(generator "eeschema")
	(generator_version "9.0")
	(paper "A3")
	(title_block
		(title "LPDDR4 Test Board")
		(date "2024-02-12")
		(rev "1.1.5")
		(comment 1 "LPDDR4 Test Board")
	)
	(text "LPDDR4 Test Board"
		(exclude_from_sim no)
		(at 15.24 20.32 0)
		(effects
			(font
				(size 2.9972 2.9972)
				(thickness 0.5994)
				(bold yes)
			)
			(justify left bottom)
		)
	)
	(symbol
		(lib_id "antmicroMechanicalParts:antmicro_logo")
		(at 86.36 269.24 0)
		(unit 1)
		(exclude_from_sim no)
		(in_bom yes)
		(on_board yes)
		(dnp no)
		(property "Reference" "N1"
			(at 91.44 267.97 0)
			(effects
				(font
					(size 1.27 1.27)
				)
				(justify left bottom)
			)
		)
		(property "Value" "antmicro_logo"
			(at 91.44 269.875 0)
			(effects
				(font
					(size 1.27 1.27)
					(thickness 0.15)
				)
				(justify left bottom)
			)
		)
		(property "Footprint" "antmicro-footprints:antmicro-logo"
			(at 101.6 279.4 0)
			(effects
				(font
					(size 1.27 1.27)
					(thickness 0.15)
				)
				(justify left bottom)
				(hide yes)
			)
		)
		(property "Datasheet" ""
			(at 101.6 281.94 0)
			(effects
				(font
					(size 1.27 1.27)
					(thickness 0.15)
				)
				(justify left bottom)
				(hide yes)
			)
		)
		(property "Description" ""
			(at 86.36 269.24 0)
			(effects
				(font
					(size 1.27 1.27)
				)
			)
		)
		(property "MPN" ""
			(at 86.36 269.24 0)
			(effects
				(font
					(size 1.27 1.27)
				)
				(hide yes)
			)
		)
		(property "Manufacturer" ""
			(at 101.6 289.56 0)
			(effects
				(font
					(size 1.27 1.27)
					(thickness 0.15)
				)
				(justify left bottom)
				(hide yes)
			)
		)
		(property "Author" "Antmicro"
			(at 101.6 284.48 0)
			(effects
				(font
					(size 1.27 1.27)
					(thickness 0.15)
				)
				(justify left bottom)
				(hide yes)
			)
		)
		(property "License" "Apache-2.0"
			(at 101.6 287.02 0)
			(effects
				(font
					(size 1.27 1.27)
					(thickness 0.15)
				)
				(justify left bottom)
				(hide yes)
			)
		)
		(instances
			(project "lpddr4-test-board"
				(path ""
					(reference "N1")
					(unit 1)
				)
			)
		)
	)
	(symbol
		(lib_id "antmicroMechanicalParts:oshw_logo")
		(at 86.36 261.62 0)
		(unit 1)
		(exclude_from_sim no)
		(in_bom yes)
		(on_board yes)
		(dnp no)
		(property "Reference" "N2"
			(at 91.44 260.35 0)
			(effects
				(font
					(size 1.27 1.27)
				)
				(justify left bottom)
			)
		)
		(property "Value" "oshw_logo"
			(at 91.5924 262.3312 0)
			(effects
				(font
					(size 1.27 1.27)
					(thickness 0.15)
				)
				(justify left bottom)
			)
		)
		(property "Footprint" "antmicro-footprints:oshw-logo"
			(at 101.6 271.78 0)
			(effects
				(font
					(size 1.27 1.27)
					(thickness 0.15)
				)
				(justify left bottom)
				(hide yes)
			)
		)
		(property "Datasheet" ""
			(at 101.6 274.32 0)
			(effects
				(font
					(size 1.27 1.27)
					(thickness 0.15)
				)
				(justify left bottom)
				(hide yes)
			)
		)
		(property "Description" ""
			(at 86.36 261.62 0)
			(effects
				(font
					(size 1.27 1.27)
				)
			)
		)
		(property "Author" "Antmicro"
			(at 101.6 276.86 0)
			(effects
				(font
					(size 1.27 1.27)
					(thickness 0.15)
				)
				(justify left bottom)
				(hide yes)
			)
		)
		(property "License" "Apache-2.0"
			(at 101.6 279.4 0)
			(effects
				(font
					(size 1.27 1.27)
					(thickness 0.15)
				)
				(justify left bottom)
				(hide yes)
			)
		)
		(property "MPN" ""
			(at 86.36 261.62 0)
			(effects
				(font
					(size 1.27 1.27)
				)
				(hide yes)
			)
		)
		(property "Manufacturer" ""
			(at 101.6 281.94 0)
			(effects
				(font
					(size 1.27 1.27)
					(thickness 0.15)
				)
				(justify left bottom)
				(hide yes)
			)
		)
		(instances
			(project "lpddr4-test-board"
				(path ""
					(reference "N2")
					(unit 1)
				)
			)
		)
	)
	(sheet
		(at 137.795 163.195)
		(size 19.05 12.7)
		(exclude_from_sim no)
		(in_bom yes)
		(on_board yes)
		(dnp no)
		(fields_autoplaced yes)
		(stroke
			(width 0)
			(type solid)
		)
		(fill
			(color 0 0 0 0.0000)
		)
		(property "Sheetname" "FPGA Banks"
			(at 137.795 162.4834 0)
			(effects
				(font
					(size 1.27 1.27)
				)
				(justify left bottom)
			)
		)
		(property "Sheetfile" "fpga-banks.kicad_sch"
			(at 137.795 176.4796 0)
			(effects
				(font
					(size 1.27 1.27)
				)
				(justify left top)
			)
		)
		(instances
			(project "lpddr4-test-board"
				(path ""
					(page "3")
				)
			)
		)
	)
	(sheet
		(at 245.11 163.195)
		(size 19.05 12.7)
		(exclude_from_sim no)
		(in_bom yes)
		(on_board yes)
		(dnp no)
		(fields_autoplaced yes)
		(stroke
			(width 0)
			(type solid)
		)
		(fill
			(color 0 0 0 0.0000)
		)
		(property "Sheetname" "Ethernet"
			(at 245.11 162.4834 0)
			(effects
				(font
					(size 1.27 1.27)
				)
				(justify left bottom)
			)
		)
		(property "Sheetfile" "ethernet.kicad_sch"
			(at 245.11 176.4796 0)
			(effects
				(font
					(size 1.27 1.27)
				)
				(justify left top)
			)
		)
		(instances
			(project "lpddr4-test-board"
				(path ""
					(page "7")
				)
			)
		)
	)
	(sheet
		(at 295.91 163.195)
		(size 19.05 12.7)
		(exclude_from_sim no)
		(in_bom yes)
		(on_board yes)
		(dnp no)
		(fields_autoplaced yes)
		(stroke
			(width 0)
			(type solid)
		)
		(fill
			(color 0 0 0 0.0000)
		)
		(property "Sheetname" "SO-DIMM"
			(at 295.91 162.4834 0)
			(effects
				(font
					(size 1.27 1.27)
				)
				(justify left bottom)
			)
		)
		(property "Sheetfile" "sodimm.kicad_sch"
			(at 295.91 176.4796 0)
			(effects
				(font
					(size 1.27 1.27)
				)
				(justify left top)
			)
		)
		(instances
			(project "lpddr4-test-board"
				(path ""
					(page "9")
				)
			)
		)
	)
	(sheet
		(at 191.135 163.195)
		(size 19.05 12.7)
		(exclude_from_sim no)
		(in_bom yes)
		(on_board yes)
		(dnp no)
		(fields_autoplaced yes)
		(stroke
			(width 0)
			(type solid)
		)
		(fill
			(color 0 0 0 0.0000)
		)
		(property "Sheetname" "Config SPI flash"
			(at 191.135 162.4834 0)
			(effects
				(font
					(size 1.27 1.27)
				)
				(justify left bottom)
			)
		)
		(property "Sheetfile" "config-spi.kicad_sch"
			(at 191.135 176.4796 0)
			(effects
				(font
					(size 1.27 1.27)
				)
				(justify left top)
			)
		)
		(instances
			(project "lpddr4-test-board"
				(path ""
					(page "5")
				)
			)
		)
	)
	(sheet
		(at 112.395 163.195)
		(size 19.05 12.7)
		(exclude_from_sim no)
		(in_bom yes)
		(on_board yes)
		(dnp no)
		(fields_autoplaced yes)
		(stroke
			(width 0)
			(type solid)
		)
		(fill
			(color 0 0 0 0.0000)
		)
		(property "Sheetname" "HyperRAM"
			(at 112.395 162.4834 0)
			(effects
				(font
					(size 1.27 1.27)
				)
				(justify left bottom)
			)
		)
		(property "Sheetfile" "hyperram.kicad_sch"
			(at 112.395 176.4796 0)
			(effects
				(font
					(size 1.27 1.27)
				)
				(justify left top)
			)
		)
		(instances
			(project "lpddr4-test-board"
				(path ""
					(page "2")
				)
			)
		)
	)
	(sheet
		(at 217.805 163.195)
		(size 19.05 12.7)
		(exclude_from_sim no)
		(in_bom yes)
		(on_board yes)
		(dnp no)
		(fields_autoplaced yes)
		(stroke
			(width 0)
			(type solid)
		)
		(fill
			(color 0 0 0 0.0000)
		)
		(property "Sheetname" "FPGA power"
			(at 217.805 162.4834 0)
			(effects
				(font
					(size 1.27 1.27)
				)
				(justify left bottom)
			)
		)
		(property "Sheetfile" "fpga-power.kicad_sch"
			(at 217.805 176.4796 0)
			(effects
				(font
					(size 1.27 1.27)
				)
				(justify left top)
			)
		)
		(instances
			(project "lpddr4-test-board"
				(path ""
					(page "6")
				)
			)
		)
	)
	(sheet
		(at 165.1 163.195)
		(size 19.05 12.7)
		(exclude_from_sim no)
		(in_bom yes)
		(on_board yes)
		(dnp no)
		(fields_autoplaced yes)
		(stroke
			(width 0)
			(type solid)
		)
		(fill
			(color 0 0 0 0.0000)
		)
		(property "Sheetname" "Interfaces"
			(at 165.1 162.4834 0)
			(effects
				(font
					(size 1.27 1.27)
				)
				(justify left bottom)
			)
		)
		(property "Sheetfile" "interfaces.kicad_sch"
			(at 165.1 176.4796 0)
			(effects
				(font
					(size 1.27 1.27)
				)
				(justify left top)
			)
		)
		(instances
			(project "lpddr4-test-board"
				(path ""
					(page "4")
				)
			)
		)
	)
	(sheet
		(at 270.51 163.195)
		(size 19.05 12.7)
		(exclude_from_sim no)
		(in_bom yes)
		(on_board yes)
		(dnp no)
		(fields_autoplaced yes)
		(stroke
			(width 0)
			(type solid)
		)
		(fill
			(color 0 0 0 0.0000)
		)
		(property "Sheetname" "Supply"
			(at 270.51 162.4834 0)
			(effects
				(font
					(size 1.27 1.27)
				)
				(justify left bottom)
			)
		)
		(property "Sheetfile" "supply.kicad_sch"
			(at 270.51 176.4796 0)
			(effects
				(font
					(size 1.27 1.27)
				)
				(justify left top)
			)
		)
		(instances
			(project "lpddr4-test-board"
				(path ""
					(page "8")
				)
			)
		)
	)
	(sheet_instances
		(path "/"
			(page "1")
		)
	)
)
